#ISCELL
  logical_power cad_note *
  *
#ISCELL
  mstr_misc dns *
  *
#ISCELL
  pure_quanta quanta_title_block_c *
  *
#ISCELL
  standard offpage *
  page146_i10
#ISCELL
  standard offpage *
  page146_i11
#ISCELL
  standard offpage *
  page146_i12
#ISCELL
  logical_power universal_gnd *
  page146_i124
#ISCELL
  standard offpage *
  page146_i125
#ISCELL
  standard offpage *
  page146_i126
#ISCELL
  standard offpage *
  page146_i127
#ISCELL
  standard offpage *
  page146_i128
#ISCELL
  standard offpage *
  page146_i13
#ISCELL
  standard offpage *
  page146_i134
#ISCELL
  standard offpage *
  page146_i135
#ISCELL
  standard offpage *
  page146_i136
#ISCELL
  standard offpage *
  page146_i137
#ISCELL
  standard offpage *
  page146_i138
#ISCELL
  standard offpage *
  page146_i139
#ISCELL
  standard offpage *
  page146_i14
#ISCELL
  standard offpage *
  page146_i140
#ISCELL
  standard offpage *
  page146_i141
#ISCELL
  standard offpage *
  page146_i142
#ISCELL
  standard offpage *
  page146_i143
#ISCELL
  logical_power universal_gnd *
  page146_i144
#CELL
  pure_quanta q_res *
  page146_i147
#CELL
  pure_quanta q_res *
  page146_i148
#ISCELL
  standard offpage *
  page146_i149
#ISCELL
  standard offpage *
  page146_i15
#ISCELL
  standard offpage *
  page146_i150
#ISCELL
  logical_power universal_gnd *
  page146_i151
#CELL
  pure_quanta q_res *
  page146_i152
#ISCELL
  standard offpage *
  page146_i153
#ISCELL
  standard offpage *
  page146_i156
#ISCELL
  standard offpage *
  page146_i158
#ISCELL
  standard offpage *
  page146_i159
#ISCELL
  logical_power universal_gnd *
  page146_i16
#ISCELL
  logical_power universal_gnd *
  page146_i163
#ISCELL
  logical_power universal_power *
  page146_i164
#CELL
  pure_quanta q_res *
  page146_i165
#CELL
  pure_quanta q_cap *
  page146_i166
#CELL
  pure_quanta q_cap *
  page146_i167
#CELL
  pure_quanta q_cap *
  page146_i168
#CELL
  pure_quanta q_cap *
  page146_i169
#ISCELL
  logical_power universal_power *
  page146_i170
#CELL
  pure_quanta q_cap *
  page146_i171
#ISCELL
  logical_power universal_gnd *
  page146_i172
#CELL
  pure_quanta q_cap *
  page146_i173
#CELL
  pure_quanta q_cap *
  page146_i174
#CELL
  pure_quanta q_cap *
  page146_i175
#ISCELL
  logical_power universal_gnd *
  page146_i176
#CELL
  pure_quanta q_cap *
  page146_i177
#ISCELL
  logical_power universal_power *
  page146_i178
#CELL
  pure_quanta q_cap *
  page146_i179
#CELL
  pure_quanta q_cap *
  page146_i180
#ISCELL
  standard offpage *
  page146_i183
#ISCELL
  standard offpage *
  page146_i184
#ISCELL
  standard offpage *
  page146_i186
#ISCELL
  standard tap *
  page146_i188
#ISCELL
  standard tap *
  page146_i189
#ISCELL
  logical_power universal_gnd *
  page146_i19
#ISCELL
  standard tap *
  page146_i191
#ISCELL
  standard tap *
  page146_i194
#ISCELL
  standard tap *
  page146_i196
#ISCELL
  standard tap *
  page146_i198
#ISCELL
  standard tap *
  page146_i199
#CELL
  pure_quanta q_res *
  page146_i20
#ISCELL
  standard tap *
  page146_i201
#ISCELL
  standard tap *
  page146_i203
#ISCELL
  standard tap *
  page146_i208
#ISCELL
  standard offpage *
  page146_i21
#ISCELL
  standard tap *
  page146_i210
#ISCELL
  standard tap *
  page146_i212
#ISCELL
  standard tap *
  page146_i213
#ISCELL
  standard tap *
  page146_i214
#ISCELL
  standard tap *
  page146_i216
#ISCELL
  standard tap *
  page146_i218
#ISCELL
  standard offpage *
  page146_i22
#ISCELL
  standard offpage *
  page146_i220
#ISCELL
  standard offpage *
  page146_i221
#ISCELL
  standard offpage *
  page146_i222
#ISCELL
  standard offpage *
  page146_i223
#ISCELL
  standard tap *
  page146_i224
#ISCELL
  standard tap *
  page146_i225
#ISCELL
  standard tap *
  page146_i226
#ISCELL
  standard tap *
  page146_i227
#ISCELL
  standard tap *
  page146_i228
#ISCELL
  standard tap *
  page146_i229
#CELL
  pure_quanta q_res *
  page146_i23
#ISCELL
  standard tap *
  page146_i230
#ISCELL
  standard tap *
  page146_i231
#ISCELL
  standard tap *
  page146_i232
#ISCELL
  standard tap *
  page146_i233
#ISCELL
  standard tap *
  page146_i234
#ISCELL
  standard tap *
  page146_i235
#ISCELL
  standard tap *
  page146_i236
#ISCELL
  standard tap *
  page146_i237
#ISCELL
  standard tap *
  page146_i238
#ISCELL
  standard tap *
  page146_i239
#ISCELL
  logical_power universal_power *
  page146_i24
#ISCELL
  standard tap *
  page146_i240
#ISCELL
  standard tap *
  page146_i241
#ISCELL
  standard tap *
  page146_i242
#ISCELL
  standard tap *
  page146_i243
#ISCELL
  standard tap *
  page146_i244
#ISCELL
  standard tap *
  page146_i245
#ISCELL
  standard tap *
  page146_i246
#ISCELL
  standard tap *
  page146_i247
#ISCELL
  standard tap *
  page146_i248
#ISCELL
  standard tap *
  page146_i249
#CELL
  pure_quanta q_res *
  page146_i25
#ISCELL
  standard tap *
  page146_i250
#ISCELL
  standard tap *
  page146_i251
#ISCELL
  standard tap *
  page146_i252
#ISCELL
  standard tap *
  page146_i253
#ISCELL
  standard tap *
  page146_i254
#ISCELL
  standard tap *
  page146_i255
#ISCELL
  logical_power universal_power *
  page146_i257
#CELL
  pure_quanta q_res *
  page146_i26
#ISCELL
  standard offpage *
  page146_i27
#ISCELL
  standard offpage *
  page146_i28
#ISCELL
  standard offpage *
  page146_i29
#ISCELL
  standard offpage *
  page146_i3
#ISCELL
  standard offpage *
  page146_i30
#CELL
  pure_quanta sconn168_me1016810202011 *
  page146_i303
#ISCELL
  standard tap *
  page146_i306
#ISCELL
  standard tap *
  page146_i307
#ISCELL
  standard tap *
  page146_i309
#CELL
  pure_quanta q_res *
  page146_i31
#ISCELL
  standard tap *
  page146_i310
#ISCELL
  standard tap *
  page146_i312
#ISCELL
  standard tap *
  page146_i313
#ISCELL
  standard tap *
  page146_i315
#ISCELL
  standard tap *
  page146_i316
#ISCELL
  standard tap *
  page146_i318
#ISCELL
  standard tap *
  page146_i319
#CELL
  pure_quanta q_res *
  page146_i32
#ISCELL
  standard tap *
  page146_i321
#ISCELL
  standard tap *
  page146_i322
#ISCELL
  standard tap *
  page146_i324
#ISCELL
  standard tap *
  page146_i325
#ISCELL
  standard tap *
  page146_i327
#ISCELL
  standard tap *
  page146_i328
#CELL
  pure_quanta q_res *
  page146_i33
#CELL
  pure_quanta q_res *
  page146_i333
#CELL
  pure_quanta q_res *
  page146_i334
#ISCELL
  standard offpage *
  page146_i335
#CELL
  pure_quanta q_res *
  page146_i336
#ISCELL
  standard offpage *
  page146_i337
#CELL
  pure_quanta q_res *
  page146_i338
#CELL
  pure_quanta q_res *
  page146_i339
#ISCELL
  standard offpage *
  page146_i34
#ISCELL
  standard offpage *
  page146_i35
#CELL
  pure_quanta q_res *
  page146_i36
#CELL
  pure_quanta q_res *
  page146_i37
#CELL
  pure_quanta q_res *
  page146_i38
#ISCELL
  standard offpage *
  page146_i39
#ISCELL
  standard offpage *
  page146_i40
#ISCELL
  standard offpage *
  page146_i41
#ISCELL
  logical_power universal_gnd *
  page146_i42
#CELL
  pure_quanta q_res *
  page146_i43
#ISCELL
  standard offpage *
  page146_i44
#ISCELL
  standard offpage *
  page146_i45
#ISCELL
  standard offpage *
  page146_i46
#ISCELL
  standard offpage *
  page146_i47
#ISCELL
  standard offpage *
  page146_i48
#ISCELL
  standard offpage *
  page146_i49
#CELL
  pure_quanta q_res *
  page146_i5
#ISCELL
  logical_power universal_power *
  page146_i51
#ISCELL
  standard offpage *
  page146_i6
#ISCELL
  standard offpage *
  page146_i7
#ISCELL
  standard offpage *
  page146_i8
#ISCELL
  standard offpage *
  page146_i9
